# SCM (Grand Teton) — schematic netlist excerpt (pin names and nets, part order shuffled) for the footprints in the layout excerpt that follows; sources: Cadence DE-HDL packaged netlist, KiCad conversion of 12092022_DA0F0TMDCD0_F0T_Management_Board_D_brd_V3_OCP.brd

R385  Q_RES  0 5% CHIP  pkg 0402LF  page 29 : A = USB_FPNL_DN ; B = USB2_01_F_DN
R373  Q_RES  120 1% CHIP  pkg 0402LF  page 20 : A = M_BMC_DDR4_MODT ; B = P1V2_AUX

(kicad_pcb
	(version 20260206)
	(generator "pcbnew")
	(generator_version "10.0")
	(general
		(thickness 1.6)
		(legacy_teardrops no)
	)
	(paper "A4")
	(title_block
		(title "12092022_DA0F0TMDCD0_F0T_Management_Board_D_brd_V3_OCP.brd")
		(comment 1 "Grand Teton / footprints 404-405 of 1440")
	)
	(layers
		(0 "F.Cu" signal "TOP")
		(4 "In1.Cu" signal "GND")
		(6 "In2.Cu" signal "IN1")
		(8 "In3.Cu" signal "GND1")
		(10 "In4.Cu" signal "IN2")
		(12 "In5.Cu" signal "VCC")
		(14 "In6.Cu" signal "VCC1")
		(16 "In7.Cu" signal "IN3")
		(18 "In8.Cu" signal "GND2")
		(20 "In9.Cu" signal "IN4")
		(22 "In10.Cu" signal "GND3")
		(2 "B.Cu" signal "BOTTOM")
		(9 "F.Adhes" user "F.Adhesive")
		(11 "B.Adhes" user "B.Adhesive")
		(13 "F.Paste" user "Package Geometry/Pastemask Top")
		(15 "B.Paste" user "Package Geometry/Pastemask Bottom")
		(5 "F.SilkS" user "Ref Des/Silkscreen Top")
		(7 "B.SilkS" user "Ref Des/Silkscreen Bottom")
		(1 "F.Mask" user "Board Geometry/Soldermask Top")
		(3 "B.Mask" user "Board Geometry/Soldermask Bottom")
		(17 "Dwgs.User" user "User.Drawings")
		(19 "Cmts.User" user "User.Comments")
		(21 "Eco1.User" user "User.Eco1")
		(23 "Eco2.User" user "User.Eco2")
		(25 "Edge.Cuts" user "Board Geometry/Outline")
		(27 "Margin" user)
		(31 "F.CrtYd" user "Package Geometry/Place Bound Top")
		(29 "B.CrtYd" user "Package Geometry/Place Bound Bottom")
		(35 "F.Fab" user "Ref Des/Assembly Top")
		(33 "B.Fab" user "Ref Des/Assembly Bottom")
	)
	(footprint ""
		(layer "F.Cu")
		(at 28.270454 -17.008602)
		(property "Reference" "R385"
			(at 0 0 0)
			(layer "F.SilkS")
			(hide yes)
			(effects
				(font
					(size 1.27 1.27)
				)
			)
		)
		(property "Value" ""
			(at 0 0 0)
			(layer "F.Fab")
			(effects
				(font
					(size 1.27 1.27)
				)
			)
		)
		(duplicate_pad_numbers_are_jumpers no)
		(fp_line
			(start -0.7874 -0.4064)
			(end 0.7874 -0.4064)
			(stroke
				(width 0.1524)
				(type default)
			)
			(layer "F.SilkS")
		)
		(fp_line
			(start 0.7874 0.4064)
			(end -0.7874 0.4064)
			(stroke
				(width 0.1524)
				(type default)
			)
			(layer "F.SilkS")
		)
		(fp_line
			(start -0.67945 -0.305054)
			(end -0.12065 -0.305054)
			(stroke
				(width 0.1)
				(type default)
			)
			(layer "F.Fab")
		)
		(fp_line
			(start -0.67945 0.3048)
			(end -0.67945 -0.305054)
			(stroke
				(width 0.1)
				(type default)
			)
			(layer "F.Fab")
		)
		(fp_line
			(start -0.12065 -0.305054)
			(end -0.12065 -0.2794)
			(stroke
				(width 0.1)
				(type default)
			)
			(layer "F.Fab")
		)
		(fp_line
			(start -0.12065 -0.2794)
			(end 0.12065 -0.2794)
			(stroke
				(width 0.1)
				(type default)
			)
			(layer "F.Fab")
		)
		(fp_line
			(start -0.12065 0.2794)
			(end -0.12065 0.3048)
			(stroke
				(width 0.1)
				(type default)
			)
			(layer "F.Fab")
		)
		(fp_line
			(start -0.12065 0.3048)
			(end -0.67945 0.3048)
			(stroke
				(width 0.1)
				(type default)
			)
			(layer "F.Fab")
		)
		(fp_line
			(start 0.120396 0.2794)
			(end -0.12065 0.2794)
			(stroke
				(width 0.1)
				(type default)
			)
			(layer "F.Fab")
		)
		(fp_line
			(start 0.120396 0.3048)
			(end 0.120396 0.2794)
			(stroke
				(width 0.1)
				(type default)
			)
			(layer "F.Fab")
		)
		(fp_line
			(start 0.12065 -0.3048)
			(end 0.67945 -0.3048)
			(stroke
				(width 0.1)
				(type default)
			)
			(layer "F.Fab")
		)
		(fp_line
			(start 0.12065 -0.2794)
			(end 0.12065 -0.3048)
			(stroke
				(width 0.1)
				(type default)
			)
			(layer "F.Fab")
		)
		(fp_line
			(start 0.67945 -0.3048)
			(end 0.67945 0.3048)
			(stroke
				(width 0.1)
				(type default)
			)
			(layer "F.Fab")
		)
		(fp_line
			(start 0.67945 0.3048)
			(end 0.120396 0.3048)
			(stroke
				(width 0.1)
				(type default)
			)
			(layer "F.Fab")
		)
		(pad "1" smd circle
			(at -0.40005 0)
			(size 0 0)
			(layers "F.Cu" "F.Mask" "F.Paste")
			(net "USB_FPNL_DN")
		)
		(pad "2" smd circle
			(at 0.40005 0)
			(size 0 0)
			(layers "F.Cu" "F.Mask" "F.Paste")
			(net "USB2_01_F_DN")
		)
	)
	(footprint ""
		(layer "F.Cu")
		(at 79.739744 -37.559488 -90)
		(property "Reference" "R373"
			(at 0 0 270)
			(layer "F.SilkS")
			(hide yes)
			(effects
				(font
					(size 1.27 1.27)
				)
			)
		)
		(property "Value" ""
			(at 0 0 270)
			(layer "F.Fab")
			(effects
				(font
					(size 1.27 1.27)
				)
			)
		)
		(duplicate_pad_numbers_are_jumpers no)
		(fp_line
			(start -0.7874 0.4064)
			(end -0.7874 -0.4064)
			(stroke
				(width 0.1524)
				(type default)
			)
			(layer "F.SilkS")
		)
		(fp_line
			(start 0.7874 0.4064)
			(end -0.7874 0.4064)
			(stroke
				(width 0.1524)
				(type default)
			)
			(layer "F.SilkS")
		)
		(fp_line
			(start -0.7874 -0.4064)
			(end 0.7874 -0.4064)
			(stroke
				(width 0.1524)
				(type default)
			)
			(layer "F.SilkS")
		)
		(fp_line
			(start 0.7874 -0.4064)
			(end 0.7874 0.4064)
			(stroke
				(width 0.1524)
				(type default)
			)
			(layer "F.SilkS")
		)
		(fp_line
			(start -0.67945 0.3048)
			(end -0.67945 -0.305054)
			(stroke
				(width 0.1)
				(type default)
			)
			(layer "F.Fab")
		)
		(fp_line
			(start -0.12065 0.3048)
			(end -0.67945 0.3048)
			(stroke
				(width 0.1)
				(type default)
			)
			(layer "F.Fab")
		)
		(fp_line
			(start 0.120396 0.3048)
			(end 0.120396 0.2794)
			(stroke
				(width 0.1)
				(type default)
			)
			(layer "F.Fab")
		)
		(fp_line
			(start 0.67945 0.3048)
			(end 0.120396 0.3048)
			(stroke
				(width 0.1)
				(type default)
			)
			(layer "F.Fab")
		)
		(fp_line
			(start -0.12065 0.2794)
			(end -0.12065 0.3048)
			(stroke
				(width 0.1)
				(type default)
			)
			(layer "F.Fab")
		)
		(fp_line
			(start 0.120396 0.2794)
			(end -0.12065 0.2794)
			(stroke
				(width 0.1)
				(type default)
			)
			(layer "F.Fab")
		)
		(fp_line
			(start -0.12065 -0.2794)
			(end 0.12065 -0.2794)
			(stroke
				(width 0.1)
				(type default)
			)
			(layer "F.Fab")
		)
		(fp_line
			(start 0.12065 -0.2794)
			(end 0.12065 -0.3048)
			(stroke
				(width 0.1)
				(type default)
			)
			(layer "F.Fab")
		)
		(fp_line
			(start 0.12065 -0.3048)
			(end 0.67945 -0.3048)
			(stroke
				(width 0.1)
				(type default)
			)
			(layer "F.Fab")
		)
		(fp_line
			(start 0.67945 -0.3048)
			(end 0.67945 0.3048)
			(stroke
				(width 0.1)
				(type default)
			)
			(layer "F.Fab")
		)
		(fp_line
			(start -0.67945 -0.305054)
			(end -0.12065 -0.305054)
			(stroke
				(width 0.1)
				(type default)
			)
			(layer "F.Fab")
		)
		(fp_line
			(start -0.12065 -0.305054)
			(end -0.12065 -0.2794)
			(stroke
				(width 0.1)
				(type default)
			)
			(layer "F.Fab")
		)
		(pad "1" smd circle
			(at -0.40005 0 270)
			(size 0 0)
			(layers "F.Cu" "F.Mask" "F.Paste")
			(net "M_BMC_DDR4_MODT")
		)
		(pad "2" smd circle
			(at 0.40005 0 270)
			(size 0 0)
			(layers "F.Cu" "F.Mask" "F.Paste")
			(net "P1V2_AUX")
		)
	)
)
